# T6G (Grand Teton) — schematic netlist excerpt (pin names and nets, part order shuffled) for the footprints in the layout excerpt that follows; sources: Cadence DE-HDL packaged netlist, KiCad conversion of 04192023_DAF0TMB3IC0_F0TG_MB_C_brd_V02_OCP.brd

U150  SN74AVC4T774PWR  IC  pkg TSSOP16XC  page 173
  DIR1  = PVDD18_S5_P0
  DIR2  = PVDD18_S5_P0
  A1  = JTAG_TCK
  A2  = JTAG_TMS
  A3  = JTAG_TRST_N
  A4  = JTAG_DBREQ_N
  DIR3  = PVDD18_S5_P0
  DIR4  = PVDD18_S5_P0
  OE  = CPU0_JTAG_BUF_OE
  GND  = GND
  B4  = JTAG_P0_R_DBREQ_N
  B3  = JTAG_P0_R_TRST_N
  B2  = JTAG_P0_R_TMS
  B1  = JTAG_P0_R_TCK
  VCCB  = PVDD18_S5_P0
  VCCA  = PVDD18_S5_P0

C38  Q_CAP  0.1UF 25V 10% X7R  pkg 0402  page 139 : A = P3V3_AUX ; B = GND

(kicad_pcb
	(version 20260206)
	(generator "pcbnew")
	(generator_version "10.0")
	(general
		(thickness 1.6)
		(legacy_teardrops no)
	)
	(paper "A4")
	(title_block
		(title "04192023_DAF0TMB3IC0_F0TG_MB_C_brd_V02_OCP.brd")
		(comment 1 "Grand Teton / footprints 3784-3785 of 8354")
	)
	(layers
		(0 "F.Cu" signal "TOP")
		(4 "In1.Cu" signal "GND")
		(6 "In2.Cu" signal "IN1")
		(8 "In3.Cu" signal "GND1")
		(10 "In4.Cu" signal "IN2")
		(12 "In5.Cu" signal "GND2")
		(14 "In6.Cu" signal "IN3")
		(16 "In7.Cu" signal "GND3")
		(18 "In8.Cu" signal "VCC")
		(20 "In9.Cu" signal "VCC1")
		(22 "In10.Cu" signal "GND4")
		(24 "In11.Cu" signal "IN4")
		(26 "In12.Cu" signal "GND5")
		(28 "In13.Cu" signal "IN5")
		(30 "In14.Cu" signal "GND6")
		(32 "In15.Cu" signal "IN6")
		(34 "In16.Cu" signal "GND7")
		(2 "B.Cu" signal "BOTTOM")
		(9 "F.Adhes" user "F.Adhesive")
		(11 "B.Adhes" user "B.Adhesive")
		(13 "F.Paste" user "Package Geometry/Pastemask Top")
		(15 "B.Paste" user "Package Geometry/Pastemask Bottom")
		(5 "F.SilkS" user "Ref Des/Silkscreen Top")
		(7 "B.SilkS" user "Ref Des/Silkscreen Bottom")
		(1 "F.Mask" user "Board Geometry/Soldermask Top")
		(3 "B.Mask" user "Board Geometry/Soldermask Bottom")
		(17 "Dwgs.User" user "User.Drawings")
		(19 "Cmts.User" user "User.Comments")
		(21 "Eco1.User" user "User.Eco1")
		(23 "Eco2.User" user "User.Eco2")
		(25 "Edge.Cuts" user "Board Geometry/Outline")
		(27 "Margin" user)
		(31 "F.CrtYd" user "Package Geometry/Place Bound Top")
		(29 "B.CrtYd" user "Package Geometry/Place Bound Bottom")
		(35 "F.Fab" user "Ref Des/Assembly Top")
		(33 "B.Fab" user "Ref Des/Assembly Bottom")
	)
	(footprint ""
		(layer "F.Cu")
		(at 252.88875 -99.065842 -90)
		(property "Reference" "U150"
			(at 1.886204 -3.446272 90)
			(unlocked yes)
			(layer "F.SilkS")
			(effects
				(font
					(size 0.7874 0.5842)
					(thickness 0.1524)
				)
				(justify left)
			)
		)
		(property "Value" ""
			(at 0 0 270)
			(layer "F.Fab")
			(effects
				(font
					(size 1.27 1.27)
				)
			)
		)
		(duplicate_pad_numbers_are_jumpers no)
		(fp_line
			(start -1.868932 2.549906)
			(end 1.868932 2.549906)
			(stroke
				(width 0.1524)
				(type default)
			)
			(layer "F.SilkS")
		)
		(fp_line
			(start 1.868932 2.549906)
			(end 1.868932 -2.549906)
			(stroke
				(width 0.1524)
				(type default)
			)
			(layer "F.SilkS")
		)
		(fp_line
			(start 0 -1.524)
			(end -1.025906 -2.549906)
			(stroke
				(width 0.1524)
				(type default)
			)
			(layer "F.SilkS")
		)
		(fp_line
			(start -1.868932 -2.549906)
			(end -1.868932 2.549906)
			(stroke
				(width 0.1524)
				(type default)
			)
			(layer "F.SilkS")
		)
		(fp_line
			(start -1.025906 -2.549906)
			(end -1.868932 -2.549906)
			(stroke
				(width 0.1524)
				(type default)
			)
			(layer "F.SilkS")
		)
		(fp_line
			(start 1.025906 -2.549906)
			(end 0 -1.524)
			(stroke
				(width 0.1524)
				(type default)
			)
			(layer "F.SilkS")
		)
		(fp_line
			(start 1.868932 -2.549906)
			(end 1.025906 -2.549906)
			(stroke
				(width 0.1524)
				(type default)
			)
			(layer "F.SilkS")
		)
		(fp_poly
			(pts
				(xy -3.7592 -2.295398) (xy -4.7752 -1.787398) (xy -4.7752 -2.803398)
			)
			(stroke
				(width 0)
				(type default)
			)
			(fill yes)
			(layer "F.SilkS")
		)
		(fp_line
			(start -2.249932 2.549906)
			(end 2.249932 2.549906)
			(stroke
				(width 0.1)
				(type default)
			)
			(layer "F.Fab")
		)
		(fp_line
			(start 2.249932 2.549906)
			(end 2.249932 -2.549906)
			(stroke
				(width 0.1)
				(type default)
			)
			(layer "F.Fab")
		)
		(fp_line
			(start -2.249932 -2.549906)
			(end -2.249932 2.549906)
			(stroke
				(width 0.1)
				(type default)
			)
			(layer "F.Fab")
		)
		(fp_line
			(start 2.249932 -2.549906)
			(end -2.249932 -2.549906)
			(stroke
				(width 0.1)
				(type default)
			)
			(layer "F.Fab")
		)
		(fp_poly
			(pts
				(xy -4.7752 -1.787398) (xy -4.7752 -2.803398) (xy -3.7592 -2.295398)
			)
			(stroke
				(width 0)
				(type default)
			)
			(fill yes)
			(layer "F.Fab")
		)
		(pad "1" smd rect
			(at -2.800096 -2.275078 180)
			(size 0.3556 1.6002)
			(layers "F.Cu" "F.Mask" "F.Paste")
			(net "PVDD18_S5_P0")
		)
		(pad "2" smd rect
			(at -2.800096 -1.625092 180)
			(size 0.3556 1.6002)
			(layers "F.Cu" "F.Mask" "F.Paste")
			(net "PVDD18_S5_P0")
		)
		(pad "3" smd rect
			(at -2.800096 -0.975106 180)
			(size 0.3556 1.6002)
			(layers "F.Cu" "F.Mask" "F.Paste")
			(net "JTAG_TCK")
		)
		(pad "4" smd rect
			(at -2.800096 -0.32512 180)
			(size 0.3556 1.6002)
			(layers "F.Cu" "F.Mask" "F.Paste")
			(net "JTAG_TMS")
		)
		(pad "5" smd rect
			(at -2.800096 0.32512 180)
			(size 0.3556 1.6002)
			(layers "F.Cu" "F.Mask" "F.Paste")
			(net "JTAG_TRST_N")
		)
		(pad "6" smd rect
			(at -2.800096 0.975106 180)
			(size 0.3556 1.6002)
			(layers "F.Cu" "F.Mask" "F.Paste")
			(net "JTAG_DBREQ_N")
		)
		(pad "7" smd rect
			(at -2.800096 1.625092 180)
			(size 0.3556 1.6002)
			(layers "F.Cu" "F.Mask" "F.Paste")
			(net "PVDD18_S5_P0")
		)
		(pad "8" smd rect
			(at -2.800096 2.275078 180)
			(size 0.3556 1.6002)
			(layers "F.Cu" "F.Mask" "F.Paste")
			(net "PVDD18_S5_P0")
		)
		(pad "9" smd rect
			(at 2.800096 2.275078 180)
			(size 0.3556 1.6002)
			(layers "F.Cu" "F.Mask" "F.Paste")
			(net "CPU0_JTAG_BUF_OE")
		)
		(pad "10" smd rect
			(at 2.800096 1.625092 180)
			(size 0.3556 1.6002)
			(layers "F.Cu" "F.Mask" "F.Paste")
			(net "GND")
		)
		(pad "11" smd rect
			(at 2.800096 0.975106 180)
			(size 0.3556 1.6002)
			(layers "F.Cu" "F.Mask" "F.Paste")
			(net "JTAG_P0_R_DBREQ_N")
		)
		(pad "12" smd rect
			(at 2.800096 0.32512 180)
			(size 0.3556 1.6002)
			(layers "F.Cu" "F.Mask" "F.Paste")
			(net "JTAG_P0_R_TRST_N")
		)
		(pad "13" smd rect
			(at 2.800096 -0.32512 180)
			(size 0.3556 1.6002)
			(layers "F.Cu" "F.Mask" "F.Paste")
			(net "JTAG_P0_R_TMS")
		)
		(pad "14" smd rect
			(at 2.800096 -0.975106 180)
			(size 0.3556 1.6002)
			(layers "F.Cu" "F.Mask" "F.Paste")
			(net "JTAG_P0_R_TCK")
		)
		(pad "15" smd rect
			(at 2.800096 -1.625092 180)
			(size 0.3556 1.6002)
			(layers "F.Cu" "F.Mask" "F.Paste")
			(net "PVDD18_S5_P0")
		)
		(pad "16" smd rect
			(at 2.800096 -2.275078 180)
			(size 0.3556 1.6002)
			(layers "F.Cu" "F.Mask" "F.Paste")
			(net "PVDD18_S5_P0")
		)
	)
	(footprint ""
		(layer "F.Cu")
		(at 92.759784 -33.06191)
		(property "Reference" "C38"
			(at 0 0 0)
			(layer "F.SilkS")
			(hide yes)
			(effects
				(font
					(size 1.27 1.27)
				)
			)
		)
		(property "Value" ""
			(at 0 0 0)
			(layer "F.Fab")
			(effects
				(font
					(size 1.27 1.27)
				)
			)
		)
		(duplicate_pad_numbers_are_jumpers no)
		(fp_line
			(start -0.7874 -0.4064)
			(end 0.7874 -0.4064)
			(stroke
				(width 0.1524)
				(type default)
			)
			(layer "F.SilkS")
		)
		(fp_line
			(start -0.7874 0.4064)
			(end -0.7874 -0.4064)
			(stroke
				(width 0.1524)
				(type default)
			)
			(layer "F.SilkS")
		)
		(fp_line
			(start 0.7874 -0.4064)
			(end 0.7874 0.4064)
			(stroke
				(width 0.1524)
				(type default)
			)
			(layer "F.SilkS")
		)
		(fp_line
			(start 0.7874 0.4064)
			(end -0.7874 0.4064)
			(stroke
				(width 0.1524)
				(type default)
			)
			(layer "F.SilkS")
		)
		(fp_line
			(start -0.67945 -0.305054)
			(end -0.12065 -0.305054)
			(stroke
				(width 0.1)
				(type default)
			)
			(layer "F.Fab")
		)
		(fp_line
			(start -0.67945 0.3048)
			(end -0.67945 -0.305054)
			(stroke
				(width 0.1)
				(type default)
			)
			(layer "F.Fab")
		)
		(fp_line
			(start -0.12065 -0.305054)
			(end -0.12065 -0.2794)
			(stroke
				(width 0.1)
				(type default)
			)
			(layer "F.Fab")
		)
		(fp_line
			(start -0.12065 -0.2794)
			(end 0.12065 -0.2794)
			(stroke
				(width 0.1)
				(type default)
			)
			(layer "F.Fab")
		)
		(fp_line
			(start -0.12065 0.2794)
			(end -0.12065 0.3048)
			(stroke
				(width 0.1)
				(type default)
			)
			(layer "F.Fab")
		)
		(fp_line
			(start -0.12065 0.3048)
			(end -0.67945 0.3048)
			(stroke
				(width 0.1)
				(type default)
			)
			(layer "F.Fab")
		)
		(fp_line
			(start 0.120396 0.2794)
			(end -0.12065 0.2794)
			(stroke
				(width 0.1)
				(type default)
			)
			(layer "F.Fab")
		)
		(fp_line
			(start 0.120396 0.3048)
			(end 0.120396 0.2794)
			(stroke
				(width 0.1)
				(type default)
			)
			(layer "F.Fab")
		)
		(fp_line
			(start 0.12065 -0.3048)
			(end 0.67945 -0.3048)
			(stroke
				(width 0.1)
				(type default)
			)
			(layer "F.Fab")
		)
		(fp_line
			(start 0.12065 -0.2794)
			(end 0.12065 -0.3048)
			(stroke
				(width 0.1)
				(type default)
			)
			(layer "F.Fab")
		)
		(fp_line
			(start 0.67945 -0.3048)
			(end 0.67945 0.3048)
			(stroke
				(width 0.1)
				(type default)
			)
			(layer "F.Fab")
		)
		(fp_line
			(start 0.67945 0.3048)
			(end 0.120396 0.3048)
			(stroke
				(width 0.1)
				(type default)
			)
			(layer "F.Fab")
		)
		(pad "1" smd circle
			(at -0.40005 0)
			(size 0 0)
			(layers "F.Cu" "F.Mask" "F.Paste")
			(net "P3V3_AUX")
		)
		(pad "2" smd circle
			(at 0.40005 0)
			(size 0 0)
			(layers "F.Cu" "F.Mask" "F.Paste")
			(net "GND")
		)
	)
)
